(kicad_pcb
	(version 20260206)
	(generator "pcbnew")
	(generator_version "10.0")
	(general
		(thickness 1.6)
		(legacy_teardrops no)
	)
	(paper "A4")
	(title_block
		(title "01162023_DA0F0TEBIF0_F0T_Expander_BD_F_brd_V02_OCP.brd")
		(comment 1 "Grand Teton / footprints 5246-5252 of 9728")
	)
	(layers
		(0 "F.Cu" signal "TOP")
		(4 "In1.Cu" signal "GND")
		(6 "In2.Cu" signal "VCC")
		(8 "In3.Cu" signal "VCC1")
		(10 "In4.Cu" signal "GND1")
		(12 "In5.Cu" signal "IN1")
		(14 "In6.Cu" signal "GND2")
		(16 "In7.Cu" signal "IN2")
		(18 "In8.Cu" signal "GND3")
		(20 "In9.Cu" signal "IN3")
		(22 "In10.Cu" signal "GND4")
		(24 "In11.Cu" signal "IN4")
		(26 "In12.Cu" signal "GND5")
		(28 "In13.Cu" signal "IN5")
		(30 "In14.Cu" signal "GND6")
		(32 "In15.Cu" signal "IN6")
		(34 "In16.Cu" signal "GND7")
		(2 "B.Cu" signal "BOTTOM")
		(9 "F.Adhes" user "F.Adhesive")
		(11 "B.Adhes" user "B.Adhesive")
		(13 "F.Paste" user "Package Geometry/Pastemask Top")
		(15 "B.Paste" user "Package Geometry/Pastemask Bottom")
		(5 "F.SilkS" user "Ref Des/Silkscreen Top")
		(7 "B.SilkS" user "Ref Des/Silkscreen Bottom")
		(1 "F.Mask" user "Board Geometry/Soldermask Top")
		(3 "B.Mask" user "Board Geometry/Soldermask Bottom")
		(17 "Dwgs.User" user "User.Drawings")
		(19 "Cmts.User" user "User.Comments")
		(21 "Eco1.User" user "User.Eco1")
		(23 "Eco2.User" user "User.Eco2")
		(25 "Edge.Cuts" user "Board Geometry/Outline")
		(27 "Margin" user)
		(31 "F.CrtYd" user "Package Geometry/Place Bound Top")
		(29 "B.CrtYd" user "Package Geometry/Place Bound Bottom")
		(35 "F.Fab" user "Ref Des/Assembly Top")
		(33 "B.Fab" user "Ref Des/Assembly Bottom")
	)
	(footprint ""
		(layer "F.Cu")
		(at 438.321196 -298.87291 -90)
		(property "Reference" "R4020"
			(at 0 0 270)
			(layer "F.SilkS")
			(hide yes)
			(effects
				(font
					(size 1.27 1.27)
				)
			)
		)
		(property "Value" ""
			(at 0 0 270)
			(layer "F.Fab")
			(effects
				(font
					(size 1.27 1.27)
				)
			)
		)
		(duplicate_pad_numbers_are_jumpers no)
		(fp_line
			(start -0.7874 0.4064)
			(end -0.7874 -0.4064)
			(stroke
				(width 0.1524)
				(type default)
			)
			(layer "F.SilkS")
		)
		(fp_line
			(start 0.7874 0.4064)
			(end -0.7874 0.4064)
			(stroke
				(width 0.1524)
				(type default)
			)
			(layer "F.SilkS")
		)
		(fp_line
			(start -0.7874 -0.4064)
			(end 0.7874 -0.4064)
			(stroke
				(width 0.1524)
				(type default)
			)
			(layer "F.SilkS")
		)
		(fp_line
			(start 0.7874 -0.4064)
			(end 0.7874 0.4064)
			(stroke
				(width 0.1524)
				(type default)
			)
			(layer "F.SilkS")
		)
		(fp_line
			(start -0.67945 0.3048)
			(end -0.67945 -0.305054)
			(stroke
				(width 0.1)
				(type default)
			)
			(layer "F.Fab")
		)
		(fp_line
			(start -0.12065 0.3048)
			(end -0.67945 0.3048)
			(stroke
				(width 0.1)
				(type default)
			)
			(layer "F.Fab")
		)
		(fp_line
			(start 0.120396 0.3048)
			(end 0.120396 0.2794)
			(stroke
				(width 0.1)
				(type default)
			)
			(layer "F.Fab")
		)
		(fp_line
			(start 0.67945 0.3048)
			(end 0.120396 0.3048)
			(stroke
				(width 0.1)
				(type default)
			)
			(layer "F.Fab")
		)
		(fp_line
			(start -0.12065 0.2794)
			(end -0.12065 0.3048)
			(stroke
				(width 0.1)
				(type default)
			)
			(layer "F.Fab")
		)
		(fp_line
			(start 0.120396 0.2794)
			(end -0.12065 0.2794)
			(stroke
				(width 0.1)
				(type default)
			)
			(layer "F.Fab")
		)
		(fp_line
			(start -0.12065 -0.2794)
			(end 0.12065 -0.2794)
			(stroke
				(width 0.1)
				(type default)
			)
			(layer "F.Fab")
		)
		(fp_line
			(start 0.12065 -0.2794)
			(end 0.12065 -0.3048)
			(stroke
				(width 0.1)
				(type default)
			)
			(layer "F.Fab")
		)
		(fp_line
			(start 0.12065 -0.3048)
			(end 0.67945 -0.3048)
			(stroke
				(width 0.1)
				(type default)
			)
			(layer "F.Fab")
		)
		(fp_line
			(start 0.67945 -0.3048)
			(end 0.67945 0.3048)
			(stroke
				(width 0.1)
				(type default)
			)
			(layer "F.Fab")
		)
		(fp_line
			(start -0.67945 -0.305054)
			(end -0.12065 -0.305054)
			(stroke
				(width 0.1)
				(type default)
			)
			(layer "F.Fab")
		)
		(fp_line
			(start -0.12065 -0.305054)
			(end -0.12065 -0.2794)
			(stroke
				(width 0.1)
				(type default)
			)
			(layer "F.Fab")
		)
		(pad "1" smd circle
			(at -0.40005 0 270)
			(size 0 0)
			(layers "F.Cu" "F.Mask" "F.Paste")
			(net "P1V8_PEX")
		)
		(pad "2" smd circle
			(at 0.40005 0 270)
			(size 0 0)
			(layers "F.Cu" "F.Mask" "F.Paste")
			(net "I2C_PEX3_HOST_R_SDA")
		)
	)
	(footprint ""
		(layer "F.Cu")
		(at 315.593984 -29.507688 -90)
		(property "Reference" "PC953"
			(at 0 0 270)
			(layer "F.SilkS")
			(hide yes)
			(effects
				(font
					(size 1.27 1.27)
				)
			)
		)
		(property "Value" ""
			(at 0 0 270)
			(layer "F.Fab")
			(effects
				(font
					(size 1.27 1.27)
				)
			)
		)
		(duplicate_pad_numbers_are_jumpers no)
		(fp_line
			(start -1.524 0.762)
			(end -1.524 -0.762)
			(stroke
				(width 0.1524)
				(type default)
			)
			(layer "F.SilkS")
		)
		(fp_line
			(start 1.524 0.762)
			(end -1.524 0.762)
			(stroke
				(width 0.1524)
				(type default)
			)
			(layer "F.SilkS")
		)
		(fp_line
			(start -1.524 -0.762)
			(end 1.524 -0.762)
			(stroke
				(width 0.1524)
				(type default)
			)
			(layer "F.SilkS")
		)
		(fp_line
			(start 1.524 -0.762)
			(end 1.524 0.762)
			(stroke
				(width 0.1524)
				(type default)
			)
			(layer "F.SilkS")
		)
		(fp_line
			(start -1.1049 0.724916)
			(end 1.1049 0.724916)
			(stroke
				(width 0.1)
				(type default)
			)
			(layer "F.Fab")
		)
		(fp_line
			(start 1.1049 0.724916)
			(end 1.1049 -0.724916)
			(stroke
				(width 0.1)
				(type default)
			)
			(layer "F.Fab")
		)
		(fp_line
			(start -1.1049 -0.724916)
			(end -1.1049 0.724916)
			(stroke
				(width 0.1)
				(type default)
			)
			(layer "F.Fab")
		)
		(fp_line
			(start 1.1049 -0.724916)
			(end -1.1049 -0.724916)
			(stroke
				(width 0.1)
				(type default)
			)
			(layer "F.Fab")
		)
		(pad "1" smd rect
			(at -0.889 0 90)
			(size 1.016 1.27)
			(layers "F.Cu" "F.Mask" "F.Paste")
			(net "P3V3_SSD11")
		)
		(pad "2" smd rect
			(at 0.889 0 90)
			(size 1.016 1.27)
			(layers "F.Cu" "F.Mask" "F.Paste")
			(net "GND")
		)
	)
	(footprint ""
		(layer "F.Cu")
		(at 369.590066 -72.766682 90)
		(property "Reference" "PR7088"
			(at 0 0 90)
			(layer "F.SilkS")
			(hide yes)
			(effects
				(font
					(size 1.27 1.27)
				)
			)
		)
		(property "Value" ""
			(at 0 0 90)
			(layer "F.Fab")
			(effects
				(font
					(size 1.27 1.27)
				)
			)
		)
		(duplicate_pad_numbers_are_jumpers no)
		(fp_line
			(start 0.7874 -0.4064)
			(end 0.7874 0.4064)
			(stroke
				(width 0.1524)
				(type default)
			)
			(layer "F.SilkS")
		)
		(fp_line
			(start -0.7874 -0.4064)
			(end 0.7874 -0.4064)
			(stroke
				(width 0.1524)
				(type default)
			)
			(layer "F.SilkS")
		)
		(fp_line
			(start 0.7874 0.4064)
			(end -0.7874 0.4064)
			(stroke
				(width 0.1524)
				(type default)
			)
			(layer "F.SilkS")
		)
		(fp_line
			(start -0.7874 0.4064)
			(end -0.7874 -0.4064)
			(stroke
				(width 0.1524)
				(type default)
			)
			(layer "F.SilkS")
		)
		(fp_line
			(start -0.12065 -0.305054)
			(end -0.12065 -0.2794)
			(stroke
				(width 0.1)
				(type default)
			)
			(layer "F.Fab")
		)
		(fp_line
			(start -0.67945 -0.305054)
			(end -0.12065 -0.305054)
			(stroke
				(width 0.1)
				(type default)
			)
			(layer "F.Fab")
		)
		(fp_line
			(start 0.67945 -0.3048)
			(end 0.67945 0.3048)
			(stroke
				(width 0.1)
				(type default)
			)
			(layer "F.Fab")
		)
		(fp_line
			(start 0.12065 -0.3048)
			(end 0.67945 -0.3048)
			(stroke
				(width 0.1)
				(type default)
			)
			(layer "F.Fab")
		)
		(fp_line
			(start 0.12065 -0.2794)
			(end 0.12065 -0.3048)
			(stroke
				(width 0.1)
				(type default)
			)
			(layer "F.Fab")
		)
		(fp_line
			(start -0.12065 -0.2794)
			(end 0.12065 -0.2794)
			(stroke
				(width 0.1)
				(type default)
			)
			(layer "F.Fab")
		)
		(fp_line
			(start 0.120396 0.2794)
			(end -0.12065 0.2794)
			(stroke
				(width 0.1)
				(type default)
			)
			(layer "F.Fab")
		)
		(fp_line
			(start -0.12065 0.2794)
			(end -0.12065 0.3048)
			(stroke
				(width 0.1)
				(type default)
			)
			(layer "F.Fab")
		)
		(fp_line
			(start 0.67945 0.3048)
			(end 0.120396 0.3048)
			(stroke
				(width 0.1)
				(type default)
			)
			(layer "F.Fab")
		)
		(fp_line
			(start 0.120396 0.3048)
			(end 0.120396 0.2794)
			(stroke
				(width 0.1)
				(type default)
			)
			(layer "F.Fab")
		)
		(fp_line
			(start -0.12065 0.3048)
			(end -0.67945 0.3048)
			(stroke
				(width 0.1)
				(type default)
			)
			(layer "F.Fab")
		)
		(fp_line
			(start -0.67945 0.3048)
			(end -0.67945 -0.305054)
			(stroke
				(width 0.1)
				(type default)
			)
			(layer "F.Fab")
		)
		(pad "1" smd circle
			(at -0.40005 0 90)
			(size 0 0)
			(layers "F.Cu" "F.Mask" "F.Paste")
			(net "P12V_SSD12_CO_ILIMIT")
		)
		(pad "2" smd circle
			(at 0.40005 0 90)
			(size 0 0)
			(layers "F.Cu" "F.Mask" "F.Paste")
			(net "GND")
		)
	)
	(footprint ""
		(layer "F.Cu")
		(at 149.235668 -308.13375 -135)
		(property "Reference" "R1265"
			(at 0 0 225)
			(layer "F.SilkS")
			(hide yes)
			(effects
				(font
					(size 1.27 1.27)
				)
			)
		)
		(property "Value" ""
			(at 0 0 225)
			(layer "F.Fab")
			(effects
				(font
					(size 1.27 1.27)
				)
			)
		)
		(duplicate_pad_numbers_are_jumpers no)
		(fp_line
			(start 0.787389 0.406267)
			(end -0.787389 0.406267)
			(stroke
				(width 0.1524)
				(type default)
			)
			(layer "F.SilkS")
		)
		(fp_line
			(start 0.787389 -0.406267)
			(end 0.787389 0.406267)
			(stroke
				(width 0.1524)
				(type default)
			)
			(layer "F.SilkS")
		)
		(fp_line
			(start -0.787389 0.406267)
			(end -0.787389 -0.406267)
			(stroke
				(width 0.1524)
				(type default)
			)
			(layer "F.SilkS")
		)
		(fp_line
			(start -0.787389 -0.406267)
			(end 0.787389 -0.406267)
			(stroke
				(width 0.1524)
				(type default)
			)
			(layer "F.SilkS")
		)
		(fp_line
			(start 0.679446 0.30479)
			(end 0.120515 0.30479)
			(stroke
				(width 0.1)
				(type default)
			)
			(layer "F.Fab")
		)
		(fp_line
			(start 0.120515 0.30479)
			(end 0.120335 0.279466)
			(stroke
				(width 0.1)
				(type default)
			)
			(layer "F.Fab")
		)
		(fp_line
			(start 0.120335 0.279466)
			(end -0.120695 0.279466)
			(stroke
				(width 0.1)
				(type default)
			)
			(layer "F.Fab")
		)
		(fp_line
			(start 0.679446 -0.30479)
			(end 0.679446 0.30479)
			(stroke
				(width 0.1)
				(type default)
			)
			(layer "F.Fab")
		)
		(fp_line
			(start -0.120515 0.30479)
			(end -0.679446 0.30479)
			(stroke
				(width 0.1)
				(type default)
			)
			(layer "F.Fab")
		)
		(fp_line
			(start -0.120695 0.279466)
			(end -0.120515 0.30479)
			(stroke
				(width 0.1)
				(type default)
			)
			(layer "F.Fab")
		)
		(fp_line
			(start 0.120695 -0.279466)
			(end 0.120515 -0.30479)
			(stroke
				(width 0.1)
				(type default)
			)
			(layer "F.Fab")
		)
		(fp_line
			(start 0.120515 -0.30479)
			(end 0.679446 -0.30479)
			(stroke
				(width 0.1)
				(type default)
			)
			(layer "F.Fab")
		)
		(fp_line
			(start -0.679446 0.30479)
			(end -0.679446 -0.305149)
			(stroke
				(width 0.1)
				(type default)
			)
			(layer "F.Fab")
		)
		(fp_line
			(start -0.120695 -0.279466)
			(end 0.120695 -0.279466)
			(stroke
				(width 0.1)
				(type default)
			)
			(layer "F.Fab")
		)
		(fp_line
			(start -0.120695 -0.304969)
			(end -0.120695 -0.279466)
			(stroke
				(width 0.1)
				(type default)
			)
			(layer "F.Fab")
		)
		(fp_line
			(start -0.679446 -0.305149)
			(end -0.120695 -0.304969)
			(stroke
				(width 0.1)
				(type default)
			)
			(layer "F.Fab")
		)
		(pad "1" smd circle
			(at -0.40005 0 225)
			(size 0 0)
			(layers "F.Cu" "F.Mask" "F.Paste")
			(net "PEX1_DBG_MODE1")
		)
		(pad "2" smd circle
			(at 0.40005 0 225)
			(size 0 0)
			(layers "F.Cu" "F.Mask" "F.Paste")
			(net "P1V8_PEX")
		)
	)
	(footprint ""
		(layer "F.Cu")
		(at 186.376818 -414.02762 180)
		(property "Reference" "R6777"
			(at 0 0 180)
			(layer "F.SilkS")
			(hide yes)
			(effects
				(font
					(size 1.27 1.27)
				)
			)
		)
		(property "Value" ""
			(at 0 0 180)
			(layer "F.Fab")
			(effects
				(font
					(size 1.27 1.27)
				)
			)
		)
		(duplicate_pad_numbers_are_jumpers no)
		(fp_line
			(start 0.7874 0.4064)
			(end -0.7874 0.4064)
			(stroke
				(width 0.1524)
				(type default)
			)
			(layer "F.SilkS")
		)
		(fp_line
			(start 0.7874 -0.4064)
			(end 0.7874 0.4064)
			(stroke
				(width 0.1524)
				(type default)
			)
			(layer "F.SilkS")
		)
		(fp_line
			(start -0.7874 0.4064)
			(end -0.7874 -0.4064)
			(stroke
				(width 0.1524)
				(type default)
			)
			(layer "F.SilkS")
		)
		(fp_line
			(start -0.7874 -0.4064)
			(end 0.7874 -0.4064)
			(stroke
				(width 0.1524)
				(type default)
			)
			(layer "F.SilkS")
		)
		(fp_line
			(start 0.67945 0.3048)
			(end 0.120396 0.3048)
			(stroke
				(width 0.1)
				(type default)
			)
			(layer "F.Fab")
		)
		(fp_line
			(start 0.67945 -0.3048)
			(end 0.67945 0.3048)
			(stroke
				(width 0.1)
				(type default)
			)
			(layer "F.Fab")
		)
		(fp_line
			(start 0.12065 -0.2794)
			(end 0.12065 -0.3048)
			(stroke
				(width 0.1)
				(type default)
			)
			(layer "F.Fab")
		)
		(fp_line
			(start 0.12065 -0.3048)
			(end 0.67945 -0.3048)
			(stroke
				(width 0.1)
				(type default)
			)
			(layer "F.Fab")
		)
		(fp_line
			(start 0.120396 0.3048)
			(end 0.120396 0.2794)
			(stroke
				(width 0.1)
				(type default)
			)
			(layer "F.Fab")
		)
		(fp_line
			(start 0.120396 0.2794)
			(end -0.12065 0.2794)
			(stroke
				(width 0.1)
				(type default)
			)
			(layer "F.Fab")
		)
		(fp_line
			(start -0.12065 0.3048)
			(end -0.67945 0.3048)
			(stroke
				(width 0.1)
				(type default)
			)
			(layer "F.Fab")
		)
		(fp_line
			(start -0.12065 0.2794)
			(end -0.12065 0.3048)
			(stroke
				(width 0.1)
				(type default)
			)
			(layer "F.Fab")
		)
		(fp_line
			(start -0.12065 -0.2794)
			(end 0.12065 -0.2794)
			(stroke
				(width 0.1)
				(type default)
			)
			(layer "F.Fab")
		)
		(fp_line
			(start -0.12065 -0.305054)
			(end -0.12065 -0.2794)
			(stroke
				(width 0.1)
				(type default)
			)
			(layer "F.Fab")
		)
		(fp_line
			(start -0.67945 0.3048)
			(end -0.67945 -0.305054)
			(stroke
				(width 0.1)
				(type default)
			)
			(layer "F.Fab")
		)
		(fp_line
			(start -0.67945 -0.305054)
			(end -0.12065 -0.305054)
			(stroke
				(width 0.1)
				(type default)
			)
			(layer "F.Fab")
		)
		(pad "1" smd circle
			(at -0.40005 0 180)
			(size 0 0)
			(layers "F.Cu" "F.Mask" "F.Paste")
			(net "HSC_UV_R2_N")
		)
		(pad "2" smd circle
			(at 0.40005 0 180)
			(size 0 0)
			(layers "F.Cu" "F.Mask" "F.Paste")
			(net "HSC_UV_R_N")
		)
	)
	(footprint ""
		(layer "F.Cu")
		(at 278.859488 -61.612526)
		(property "Reference" "PD44"
			(at -3.726688 -2.648204 0)
			(unlocked yes)
			(layer "F.SilkS")
			(effects
				(font
					(size 0.7874 0.5842)
					(thickness 0.1524)
				)
				(justify left)
			)
		)
		(property "Value" ""
			(at 0 0 0)
			(layer "F.Fab")
			(effects
				(font
					(size 1.27 1.27)
				)
			)
		)
		(duplicate_pad_numbers_are_jumpers no)
		(fp_line
			(start -3.656584 -1.970024)
			(end -3.656584 1.970024)
			(stroke
				(width 0.1524)
				(type default)
			)
			(layer "F.SilkS")
		)
		(fp_line
			(start -3.656584 1.970024)
			(end 4.240784 1.970024)
			(stroke
				(width 0.1524)
				(type default)
			)
			(layer "F.SilkS")
		)
		(fp_line
			(start 4.240784 -1.970024)
			(end -3.656584 -1.970024)
			(stroke
				(width 0.1524)
				(type default)
			)
			(layer "F.SilkS")
		)
		(fp_line
			(start 4.240784 1.970024)
			(end 4.240784 -1.970024)
			(stroke
				(width 0.1524)
				(type default)
			)
			(layer "F.SilkS")
		)
		(fp_poly
			(pts
				(xy 3.580384 1.970024) (xy 3.580384 -1.970024) (xy 4.240784 -1.970024) (xy 4.240784 1.970024)
			)
			(stroke
				(width 0)
				(type default)
			)
			(fill yes)
			(layer "F.SilkS")
		)
		(fp_line
			(start -2.3749 -1.970024)
			(end -2.3749 1.970024)
			(stroke
				(width 0.1)
				(type default)
			)
			(layer "F.Fab")
		)
		(fp_line
			(start -2.3749 1.970024)
			(end 2.3749 1.970024)
			(stroke
				(width 0.1)
				(type default)
			)
			(layer "F.Fab")
		)
		(fp_line
			(start 2.3749 -1.970024)
			(end -2.3749 -1.970024)
			(stroke
				(width 0.1)
				(type default)
			)
			(layer "F.Fab")
		)
		(fp_line
			(start 2.3749 1.970024)
			(end 2.3749 -1.970024)
			(stroke
				(width 0.1)
				(type default)
			)
			(layer "F.Fab")
		)
		(fp_text user "+"
			(at -4.9784 -0.23495 0)
			(unlocked yes)
			(layer "F.Fab")
			(effects
				(font
					(size 1.905 1.4224)
					(thickness 0.1524)
				)
				(justify left)
			)
		)
		(fp_text user "-"
			(at 4.1656 -0.23495 0)
			(unlocked yes)
			(layer "F.Fab")
			(effects
				(font
					(size 1.905 1.4224)
					(thickness 0.1524)
				)
				(justify left)
			)
		)
		(pad "A" smd rect
			(at -2.450084 0)
			(size 2.159 2.2606)
			(layers "F.Cu" "F.Mask" "F.Paste")
			(net "GND")
		)
		(pad "C" smd rect
			(at 2.450084 0)
			(size 2.159 2.2606)
			(layers "F.Cu" "F.Mask" "F.Paste")
			(net "P12V_AUX")
		)
	)
	(footprint ""
		(layer "F.Cu")
		(at 449.120514 -70.307454 90)
		(property "Reference" "PC879"
			(at 0 0 90)
			(layer "F.SilkS")
			(hide yes)
			(effects
				(font
					(size 1.27 1.27)
				)
			)
		)
		(property "Value" ""
			(at 0 0 90)
			(layer "F.Fab")
			(effects
				(font
					(size 1.27 1.27)
				)
			)
		)
		(duplicate_pad_numbers_are_jumpers no)
		(fp_line
			(start 0.7874 -0.4064)
			(end 0.7874 0.4064)
			(stroke
				(width 0.1524)
				(type default)
			)
			(layer "F.SilkS")
		)
		(fp_line
			(start -0.7874 -0.4064)
			(end 0.7874 -0.4064)
			(stroke
				(width 0.1524)
				(type default)
			)
			(layer "F.SilkS")
		)
		(fp_line
			(start 0.7874 0.4064)
			(end -0.7874 0.4064)
			(stroke
				(width 0.1524)
				(type default)
			)
			(layer "F.SilkS")
		)
		(fp_line
			(start -0.7874 0.4064)
			(end -0.7874 -0.4064)
			(stroke
				(width 0.1524)
				(type default)
			)
			(layer "F.SilkS")
		)
		(fp_line
			(start -0.12065 -0.305054)
			(end -0.12065 -0.2794)
			(stroke
				(width 0.1)
				(type default)
			)
			(layer "F.Fab")
		)
		(fp_line
			(start -0.67945 -0.305054)
			(end -0.12065 -0.305054)
			(stroke
				(width 0.1)
				(type default)
			)
			(layer "F.Fab")
		)
		(fp_line
			(start 0.67945 -0.3048)
			(end 0.67945 0.3048)
			(stroke
				(width 0.1)
				(type default)
			)
			(layer "F.Fab")
		)
		(fp_line
			(start 0.12065 -0.3048)
			(end 0.67945 -0.3048)
			(stroke
				(width 0.1)
				(type default)
			)
			(layer "F.Fab")
		)
		(fp_line
			(start 0.12065 -0.2794)
			(end 0.12065 -0.3048)
			(stroke
				(width 0.1)
				(type default)
			)
			(layer "F.Fab")
		)
		(fp_line
			(start -0.12065 -0.2794)
			(end 0.12065 -0.2794)
			(stroke
				(width 0.1)
				(type default)
			)
			(layer "F.Fab")
		)
		(fp_line
			(start 0.120396 0.2794)
			(end -0.12065 0.2794)
			(stroke
				(width 0.1)
				(type default)
			)
			(layer "F.Fab")
		)
		(fp_line
			(start -0.12065 0.2794)
			(end -0.12065 0.3048)
			(stroke
				(width 0.1)
				(type default)
			)
			(layer "F.Fab")
		)
		(fp_line
			(start 0.67945 0.3048)
			(end 0.120396 0.3048)
			(stroke
				(width 0.1)
				(type default)
			)
			(layer "F.Fab")
		)
		(fp_line
			(start 0.120396 0.3048)
			(end 0.120396 0.2794)
			(stroke
				(width 0.1)
				(type default)
			)
			(layer "F.Fab")
		)
		(fp_line
			(start -0.12065 0.3048)
			(end -0.67945 0.3048)
			(stroke
				(width 0.1)
				(type default)
			)
			(layer "F.Fab")
		)
		(fp_line
			(start -0.67945 0.3048)
			(end -0.67945 -0.305054)
			(stroke
				(width 0.1)
				(type default)
			)
			(layer "F.Fab")
		)
		(pad "1" smd circle
			(at -0.40005 0 90)
			(size 0 0)
			(layers "F.Cu" "F.Mask" "F.Paste")
			(net "P12V_AUX")
		)
		(pad "2" smd circle
			(at 0.40005 0 90)
			(size 0 0)
			(layers "F.Cu" "F.Mask" "F.Paste")
			(net "GND")
		)
	)
)
